(kicad_pcb
	(version 20260206)
	(generator "pcbnew")
	(generator_version "10.0")
	(general
		(thickness 1.6)
		(legacy_teardrops no)
	)
	(paper "A4")
	(title_block
		(title "01162023_DA0F0TEBIF0_F0T_Expander_BD_F_brd_V02_OCP.brd")
		(comment 1 "Grand Teton / footprints 2306-2312 of 9728")
	)
	(layers
		(0 "F.Cu" signal "TOP")
		(4 "In1.Cu" signal "GND")
		(6 "In2.Cu" signal "VCC")
		(8 "In3.Cu" signal "VCC1")
		(10 "In4.Cu" signal "GND1")
		(12 "In5.Cu" signal "IN1")
		(14 "In6.Cu" signal "GND2")
		(16 "In7.Cu" signal "IN2")
		(18 "In8.Cu" signal "GND3")
		(20 "In9.Cu" signal "IN3")
		(22 "In10.Cu" signal "GND4")
		(24 "In11.Cu" signal "IN4")
		(26 "In12.Cu" signal "GND5")
		(28 "In13.Cu" signal "IN5")
		(30 "In14.Cu" signal "GND6")
		(32 "In15.Cu" signal "IN6")
		(34 "In16.Cu" signal "GND7")
		(2 "B.Cu" signal "BOTTOM")
		(9 "F.Adhes" user "F.Adhesive")
		(11 "B.Adhes" user "B.Adhesive")
		(13 "F.Paste" user "Package Geometry/Pastemask Top")
		(15 "B.Paste" user "Package Geometry/Pastemask Bottom")
		(5 "F.SilkS" user "Ref Des/Silkscreen Top")
		(7 "B.SilkS" user "Ref Des/Silkscreen Bottom")
		(1 "F.Mask" user "Board Geometry/Soldermask Top")
		(3 "B.Mask" user "Board Geometry/Soldermask Bottom")
		(17 "Dwgs.User" user "User.Drawings")
		(19 "Cmts.User" user "User.Comments")
		(21 "Eco1.User" user "User.Eco1")
		(23 "Eco2.User" user "User.Eco2")
		(25 "Edge.Cuts" user "Board Geometry/Outline")
		(27 "Margin" user)
		(31 "F.CrtYd" user "Package Geometry/Place Bound Top")
		(29 "B.CrtYd" user "Package Geometry/Place Bound Bottom")
		(35 "F.Fab" user "Ref Des/Assembly Top")
		(33 "B.Fab" user "Ref Des/Assembly Bottom")
	)
	(footprint ""
		(layer "F.Cu")
		(at 191.0461 -414.587436 -90)
		(property "Reference" "C4478"
			(at 0 0 270)
			(layer "F.SilkS")
			(hide yes)
			(effects
				(font
					(size 1.27 1.27)
				)
			)
		)
		(property "Value" ""
			(at 0 0 270)
			(layer "F.Fab")
			(effects
				(font
					(size 1.27 1.27)
				)
			)
		)
		(duplicate_pad_numbers_are_jumpers no)
		(fp_line
			(start -0.7874 0.4064)
			(end -0.7874 -0.4064)
			(stroke
				(width 0.1524)
				(type default)
			)
			(layer "F.SilkS")
		)
		(fp_line
			(start 0.7874 0.4064)
			(end -0.7874 0.4064)
			(stroke
				(width 0.1524)
				(type default)
			)
			(layer "F.SilkS")
		)
		(fp_line
			(start -0.7874 -0.4064)
			(end 0.7874 -0.4064)
			(stroke
				(width 0.1524)
				(type default)
			)
			(layer "F.SilkS")
		)
		(fp_line
			(start 0.7874 -0.4064)
			(end 0.7874 0.4064)
			(stroke
				(width 0.1524)
				(type default)
			)
			(layer "F.SilkS")
		)
		(fp_line
			(start -0.67945 0.3048)
			(end -0.67945 -0.305054)
			(stroke
				(width 0.1)
				(type default)
			)
			(layer "F.Fab")
		)
		(fp_line
			(start -0.12065 0.3048)
			(end -0.67945 0.3048)
			(stroke
				(width 0.1)
				(type default)
			)
			(layer "F.Fab")
		)
		(fp_line
			(start 0.120396 0.3048)
			(end 0.120396 0.2794)
			(stroke
				(width 0.1)
				(type default)
			)
			(layer "F.Fab")
		)
		(fp_line
			(start 0.67945 0.3048)
			(end 0.120396 0.3048)
			(stroke
				(width 0.1)
				(type default)
			)
			(layer "F.Fab")
		)
		(fp_line
			(start -0.12065 0.2794)
			(end -0.12065 0.3048)
			(stroke
				(width 0.1)
				(type default)
			)
			(layer "F.Fab")
		)
		(fp_line
			(start 0.120396 0.2794)
			(end -0.12065 0.2794)
			(stroke
				(width 0.1)
				(type default)
			)
			(layer "F.Fab")
		)
		(fp_line
			(start -0.12065 -0.2794)
			(end 0.12065 -0.2794)
			(stroke
				(width 0.1)
				(type default)
			)
			(layer "F.Fab")
		)
		(fp_line
			(start 0.12065 -0.2794)
			(end 0.12065 -0.3048)
			(stroke
				(width 0.1)
				(type default)
			)
			(layer "F.Fab")
		)
		(fp_line
			(start 0.12065 -0.3048)
			(end 0.67945 -0.3048)
			(stroke
				(width 0.1)
				(type default)
			)
			(layer "F.Fab")
		)
		(fp_line
			(start 0.67945 -0.3048)
			(end 0.67945 0.3048)
			(stroke
				(width 0.1)
				(type default)
			)
			(layer "F.Fab")
		)
		(fp_line
			(start -0.67945 -0.305054)
			(end -0.12065 -0.305054)
			(stroke
				(width 0.1)
				(type default)
			)
			(layer "F.Fab")
		)
		(fp_line
			(start -0.12065 -0.305054)
			(end -0.12065 -0.2794)
			(stroke
				(width 0.1)
				(type default)
			)
			(layer "F.Fab")
		)
		(pad "1" smd circle
			(at -0.40005 0 270)
			(size 0 0)
			(layers "F.Cu" "F.Mask" "F.Paste")
			(net "P12V_AUX_FP_TRIGGER")
		)
		(pad "2" smd circle
			(at 0.40005 0 270)
			(size 0 0)
			(layers "F.Cu" "F.Mask" "F.Paste")
			(net "GND")
		)
	)
	(footprint ""
		(layer "F.Cu")
		(at 249.020838 -119.140986 90)
		(property "Reference" "PC900"
			(at 0 0 90)
			(layer "F.SilkS")
			(hide yes)
			(effects
				(font
					(size 1.27 1.27)
				)
			)
		)
		(property "Value" ""
			(at 0 0 90)
			(layer "F.Fab")
			(effects
				(font
					(size 1.27 1.27)
				)
			)
		)
		(duplicate_pad_numbers_are_jumpers no)
		(fp_line
			(start 0.7874 -0.4064)
			(end 0.7874 0.4064)
			(stroke
				(width 0.1524)
				(type default)
			)
			(layer "F.SilkS")
		)
		(fp_line
			(start -0.7874 -0.4064)
			(end 0.7874 -0.4064)
			(stroke
				(width 0.1524)
				(type default)
			)
			(layer "F.SilkS")
		)
		(fp_line
			(start 0.7874 0.4064)
			(end -0.7874 0.4064)
			(stroke
				(width 0.1524)
				(type default)
			)
			(layer "F.SilkS")
		)
		(fp_line
			(start -0.7874 0.4064)
			(end -0.7874 -0.4064)
			(stroke
				(width 0.1524)
				(type default)
			)
			(layer "F.SilkS")
		)
		(fp_line
			(start -0.12065 -0.305054)
			(end -0.12065 -0.2794)
			(stroke
				(width 0.1)
				(type default)
			)
			(layer "F.Fab")
		)
		(fp_line
			(start -0.67945 -0.305054)
			(end -0.12065 -0.305054)
			(stroke
				(width 0.1)
				(type default)
			)
			(layer "F.Fab")
		)
		(fp_line
			(start 0.67945 -0.3048)
			(end 0.67945 0.3048)
			(stroke
				(width 0.1)
				(type default)
			)
			(layer "F.Fab")
		)
		(fp_line
			(start 0.12065 -0.3048)
			(end 0.67945 -0.3048)
			(stroke
				(width 0.1)
				(type default)
			)
			(layer "F.Fab")
		)
		(fp_line
			(start 0.12065 -0.2794)
			(end 0.12065 -0.3048)
			(stroke
				(width 0.1)
				(type default)
			)
			(layer "F.Fab")
		)
		(fp_line
			(start -0.12065 -0.2794)
			(end 0.12065 -0.2794)
			(stroke
				(width 0.1)
				(type default)
			)
			(layer "F.Fab")
		)
		(fp_line
			(start 0.120396 0.2794)
			(end -0.12065 0.2794)
			(stroke
				(width 0.1)
				(type default)
			)
			(layer "F.Fab")
		)
		(fp_line
			(start -0.12065 0.2794)
			(end -0.12065 0.3048)
			(stroke
				(width 0.1)
				(type default)
			)
			(layer "F.Fab")
		)
		(fp_line
			(start 0.67945 0.3048)
			(end 0.120396 0.3048)
			(stroke
				(width 0.1)
				(type default)
			)
			(layer "F.Fab")
		)
		(fp_line
			(start 0.120396 0.3048)
			(end 0.120396 0.2794)
			(stroke
				(width 0.1)
				(type default)
			)
			(layer "F.Fab")
		)
		(fp_line
			(start -0.12065 0.3048)
			(end -0.67945 0.3048)
			(stroke
				(width 0.1)
				(type default)
			)
			(layer "F.Fab")
		)
		(fp_line
			(start -0.67945 0.3048)
			(end -0.67945 -0.305054)
			(stroke
				(width 0.1)
				(type default)
			)
			(layer "F.Fab")
		)
		(pad "1" smd circle
			(at -0.40005 0 90)
			(size 0 0)
			(layers "F.Cu" "F.Mask" "F.Paste")
			(net "P3V3_NIC4_CO_GATE")
		)
		(pad "2" smd circle
			(at 0.40005 0 90)
			(size 0 0)
			(layers "F.Cu" "F.Mask" "F.Paste")
			(net "GND")
		)
	)
	(footprint ""
		(layer "F.Cu")
		(at 332.045564 -343.952322 90)
		(property "Reference" "C568"
			(at 0 0 90)
			(layer "F.SilkS")
			(hide yes)
			(effects
				(font
					(size 1.27 1.27)
				)
			)
		)
		(property "Value" ""
			(at 0 0 90)
			(layer "F.Fab")
			(effects
				(font
					(size 1.27 1.27)
				)
			)
		)
		(duplicate_pad_numbers_are_jumpers no)
		(fp_line
			(start 0.299974 -0.150114)
			(end 0.299974 0.150114)
			(stroke
				(width 0.1)
				(type default)
			)
			(layer "F.Fab")
		)
		(fp_line
			(start -0.299974 -0.150114)
			(end 0.299974 -0.150114)
			(stroke
				(width 0.1)
				(type default)
			)
			(layer "F.Fab")
		)
		(fp_line
			(start 0.299974 0.150114)
			(end -0.299974 0.150114)
			(stroke
				(width 0.1)
				(type default)
			)
			(layer "F.Fab")
		)
		(fp_line
			(start -0.299974 0.150114)
			(end -0.299974 -0.150114)
			(stroke
				(width 0.1)
				(type default)
			)
			(layer "F.Fab")
		)
		(pad "1" smd rect
			(at -0.2667 0 90)
			(size 0.3048 0.381)
			(layers "F.Cu" "F.Mask" "F.Paste")
			(net "P5E_PEX2_STN6_TX_DN<103>")
		)
		(pad "2" smd rect
			(at 0.2667 0 90)
			(size 0.3048 0.381)
			(layers "F.Cu" "F.Mask" "F.Paste")
			(net "P5E_PEX2_STN6_TX_C_DN<103>")
		)
	)
	(footprint ""
		(layer "F.Cu")
		(at 358.971088 -272.15846 -90)
		(property "Reference" "PL14"
			(at 1.491996 -3.25882 90)
			(unlocked yes)
			(layer "F.SilkS")
			(effects
				(font
					(size 0.7874 0.5842)
					(thickness 0.1524)
				)
				(justify left)
			)
		)
		(property "Value" ""
			(at 0 0 270)
			(layer "F.Fab")
			(effects
				(font
					(size 1.27 1.27)
				)
			)
		)
		(duplicate_pad_numbers_are_jumpers no)
		(fp_line
			(start -2.249932 2.249932)
			(end -2.249932 1.3843)
			(stroke
				(width 0.1524)
				(type default)
			)
			(layer "F.SilkS")
		)
		(fp_line
			(start 2.249932 2.249932)
			(end -2.249932 2.249932)
			(stroke
				(width 0.1524)
				(type default)
			)
			(layer "F.SilkS")
		)
		(fp_line
			(start 2.249932 1.3843)
			(end 2.249932 2.249932)
			(stroke
				(width 0.1524)
				(type default)
			)
			(layer "F.SilkS")
		)
		(fp_line
			(start -2.249932 -1.3843)
			(end -2.249932 -2.249932)
			(stroke
				(width 0.1524)
				(type default)
			)
			(layer "F.SilkS")
		)
		(fp_line
			(start -2.249932 -2.249932)
			(end 2.249932 -2.249932)
			(stroke
				(width 0.1524)
				(type default)
			)
			(layer "F.SilkS")
		)
		(fp_line
			(start 2.249932 -2.249932)
			(end 2.249932 -1.3843)
			(stroke
				(width 0.1524)
				(type default)
			)
			(layer "F.SilkS")
		)
		(fp_line
			(start -2.249932 2.249932)
			(end -2.249932 -2.249932)
			(stroke
				(width 0.1)
				(type default)
			)
			(layer "F.Fab")
		)
		(fp_line
			(start 2.249932 2.249932)
			(end -2.249932 2.249932)
			(stroke
				(width 0.1)
				(type default)
			)
			(layer "F.Fab")
		)
		(fp_line
			(start -2.249932 -2.249932)
			(end 2.249932 -2.249932)
			(stroke
				(width 0.1)
				(type default)
			)
			(layer "F.Fab")
		)
		(fp_line
			(start 2.249932 -2.249932)
			(end 2.249932 2.249932)
			(stroke
				(width 0.1)
				(type default)
			)
			(layer "F.Fab")
		)
		(pad "1" smd rect
			(at -1.82499 0 270)
			(size 1.0668 2.5146)
			(layers "F.Cu" "F.Mask" "F.Paste")
			(net "SW_P12V_P0V8_PEX3_FLT")
		)
		(pad "2" smd rect
			(at 1.82499 0 270)
			(size 1.0668 2.5146)
			(layers "F.Cu" "F.Mask" "F.Paste")
			(net "P12V_AUX")
		)
	)
	(footprint ""
		(layer "F.Cu")
		(at 368.539776 -152.71115 90)
		(property "Reference" "R749"
			(at 0 0 90)
			(layer "F.SilkS")
			(hide yes)
			(effects
				(font
					(size 1.27 1.27)
				)
			)
		)
		(property "Value" ""
			(at 0 0 90)
			(layer "F.Fab")
			(effects
				(font
					(size 1.27 1.27)
				)
			)
		)
		(duplicate_pad_numbers_are_jumpers no)
		(fp_line
			(start 0.7874 -0.4064)
			(end 0.7874 0.4064)
			(stroke
				(width 0.1524)
				(type default)
			)
			(layer "F.SilkS")
		)
		(fp_line
			(start -0.7874 -0.4064)
			(end 0.7874 -0.4064)
			(stroke
				(width 0.1524)
				(type default)
			)
			(layer "F.SilkS")
		)
		(fp_line
			(start 0.7874 0.4064)
			(end -0.7874 0.4064)
			(stroke
				(width 0.1524)
				(type default)
			)
			(layer "F.SilkS")
		)
		(fp_line
			(start -0.7874 0.4064)
			(end -0.7874 -0.4064)
			(stroke
				(width 0.1524)
				(type default)
			)
			(layer "F.SilkS")
		)
		(fp_line
			(start -0.12065 -0.305054)
			(end -0.12065 -0.2794)
			(stroke
				(width 0.1)
				(type default)
			)
			(layer "F.Fab")
		)
		(fp_line
			(start -0.67945 -0.305054)
			(end -0.12065 -0.305054)
			(stroke
				(width 0.1)
				(type default)
			)
			(layer "F.Fab")
		)
		(fp_line
			(start 0.67945 -0.3048)
			(end 0.67945 0.3048)
			(stroke
				(width 0.1)
				(type default)
			)
			(layer "F.Fab")
		)
		(fp_line
			(start 0.12065 -0.3048)
			(end 0.67945 -0.3048)
			(stroke
				(width 0.1)
				(type default)
			)
			(layer "F.Fab")
		)
		(fp_line
			(start 0.12065 -0.2794)
			(end 0.12065 -0.3048)
			(stroke
				(width 0.1)
				(type default)
			)
			(layer "F.Fab")
		)
		(fp_line
			(start -0.12065 -0.2794)
			(end 0.12065 -0.2794)
			(stroke
				(width 0.1)
				(type default)
			)
			(layer "F.Fab")
		)
		(fp_line
			(start 0.120396 0.2794)
			(end -0.12065 0.2794)
			(stroke
				(width 0.1)
				(type default)
			)
			(layer "F.Fab")
		)
		(fp_line
			(start -0.12065 0.2794)
			(end -0.12065 0.3048)
			(stroke
				(width 0.1)
				(type default)
			)
			(layer "F.Fab")
		)
		(fp_line
			(start 0.67945 0.3048)
			(end 0.120396 0.3048)
			(stroke
				(width 0.1)
				(type default)
			)
			(layer "F.Fab")
		)
		(fp_line
			(start 0.120396 0.3048)
			(end 0.120396 0.2794)
			(stroke
				(width 0.1)
				(type default)
			)
			(layer "F.Fab")
		)
		(fp_line
			(start -0.12065 0.3048)
			(end -0.67945 0.3048)
			(stroke
				(width 0.1)
				(type default)
			)
			(layer "F.Fab")
		)
		(fp_line
			(start -0.67945 0.3048)
			(end -0.67945 -0.305054)
			(stroke
				(width 0.1)
				(type default)
			)
			(layer "F.Fab")
		)
		(pad "1" smd circle
			(at -0.40005 0 90)
			(size 0 0)
			(layers "F.Cu" "F.Mask" "F.Paste")
			(net "NIC6_ADC_A0")
		)
		(pad "2" smd circle
			(at 0.40005 0 90)
			(size 0 0)
			(layers "F.Cu" "F.Mask" "F.Paste")
			(net "P3V3_AUX")
		)
	)
	(footprint ""
		(layer "F.Cu")
		(at 450.682106 -366.29594 -90)
		(property "Reference" "R6693"
			(at 0 0 270)
			(layer "F.SilkS")
			(hide yes)
			(effects
				(font
					(size 1.27 1.27)
				)
			)
		)
		(property "Value" ""
			(at 0 0 270)
			(layer "F.Fab")
			(effects
				(font
					(size 1.27 1.27)
				)
			)
		)
		(duplicate_pad_numbers_are_jumpers no)
		(fp_line
			(start -0.7874 0.4064)
			(end -0.7874 -0.4064)
			(stroke
				(width 0.1524)
				(type default)
			)
			(layer "F.SilkS")
		)
		(fp_line
			(start 0.7874 0.4064)
			(end -0.7874 0.4064)
			(stroke
				(width 0.1524)
				(type default)
			)
			(layer "F.SilkS")
		)
		(fp_line
			(start -0.7874 -0.4064)
			(end 0.7874 -0.4064)
			(stroke
				(width 0.1524)
				(type default)
			)
			(layer "F.SilkS")
		)
		(fp_line
			(start 0.7874 -0.4064)
			(end 0.7874 0.4064)
			(stroke
				(width 0.1524)
				(type default)
			)
			(layer "F.SilkS")
		)
		(fp_line
			(start -0.67945 0.3048)
			(end -0.67945 -0.305054)
			(stroke
				(width 0.1)
				(type default)
			)
			(layer "F.Fab")
		)
		(fp_line
			(start -0.12065 0.3048)
			(end -0.67945 0.3048)
			(stroke
				(width 0.1)
				(type default)
			)
			(layer "F.Fab")
		)
		(fp_line
			(start 0.120396 0.3048)
			(end 0.120396 0.2794)
			(stroke
				(width 0.1)
				(type default)
			)
			(layer "F.Fab")
		)
		(fp_line
			(start 0.67945 0.3048)
			(end 0.120396 0.3048)
			(stroke
				(width 0.1)
				(type default)
			)
			(layer "F.Fab")
		)
		(fp_line
			(start -0.12065 0.2794)
			(end -0.12065 0.3048)
			(stroke
				(width 0.1)
				(type default)
			)
			(layer "F.Fab")
		)
		(fp_line
			(start 0.120396 0.2794)
			(end -0.12065 0.2794)
			(stroke
				(width 0.1)
				(type default)
			)
			(layer "F.Fab")
		)
		(fp_line
			(start -0.12065 -0.2794)
			(end 0.12065 -0.2794)
			(stroke
				(width 0.1)
				(type default)
			)
			(layer "F.Fab")
		)
		(fp_line
			(start 0.12065 -0.2794)
			(end 0.12065 -0.3048)
			(stroke
				(width 0.1)
				(type default)
			)
			(layer "F.Fab")
		)
		(fp_line
			(start 0.12065 -0.3048)
			(end 0.67945 -0.3048)
			(stroke
				(width 0.1)
				(type default)
			)
			(layer "F.Fab")
		)
		(fp_line
			(start 0.67945 -0.3048)
			(end 0.67945 0.3048)
			(stroke
				(width 0.1)
				(type default)
			)
			(layer "F.Fab")
		)
		(fp_line
			(start -0.67945 -0.305054)
			(end -0.12065 -0.305054)
			(stroke
				(width 0.1)
				(type default)
			)
			(layer "F.Fab")
		)
		(fp_line
			(start -0.12065 -0.305054)
			(end -0.12065 -0.2794)
			(stroke
				(width 0.1)
				(type default)
			)
			(layer "F.Fab")
		)
		(pad "1" smd circle
			(at -0.40005 0 270)
			(size 0 0)
			(layers "F.Cu" "F.Mask" "F.Paste")
			(net "GPU_3V3IO_RSVD4")
		)
		(pad "2" smd circle
			(at 0.40005 0 270)
			(size 0 0)
			(layers "F.Cu" "F.Mask" "F.Paste")
			(net "GND")
		)
	)
	(footprint ""
		(layer "F.Cu")
		(at 340.561422 -193.46545 180)
		(property "Reference" "R4248"
			(at 0 0 180)
			(layer "F.SilkS")
			(hide yes)
			(effects
				(font
					(size 1.27 1.27)
				)
			)
		)
		(property "Value" ""
			(at 0 0 180)
			(layer "F.Fab")
			(effects
				(font
					(size 1.27 1.27)
				)
			)
		)
		(duplicate_pad_numbers_are_jumpers no)
		(fp_line
			(start 0.7874 0.4064)
			(end -0.7874 0.4064)
			(stroke
				(width 0.1524)
				(type default)
			)
			(layer "F.SilkS")
		)
		(fp_line
			(start 0.7874 -0.4064)
			(end 0.7874 0.4064)
			(stroke
				(width 0.1524)
				(type default)
			)
			(layer "F.SilkS")
		)
		(fp_line
			(start -0.7874 0.4064)
			(end -0.7874 -0.4064)
			(stroke
				(width 0.1524)
				(type default)
			)
			(layer "F.SilkS")
		)
		(fp_line
			(start -0.7874 -0.4064)
			(end 0.7874 -0.4064)
			(stroke
				(width 0.1524)
				(type default)
			)
			(layer "F.SilkS")
		)
		(fp_line
			(start 0.67945 0.3048)
			(end 0.120396 0.3048)
			(stroke
				(width 0.1)
				(type default)
			)
			(layer "F.Fab")
		)
		(fp_line
			(start 0.67945 -0.3048)
			(end 0.67945 0.3048)
			(stroke
				(width 0.1)
				(type default)
			)
			(layer "F.Fab")
		)
		(fp_line
			(start 0.12065 -0.2794)
			(end 0.12065 -0.3048)
			(stroke
				(width 0.1)
				(type default)
			)
			(layer "F.Fab")
		)
		(fp_line
			(start 0.12065 -0.3048)
			(end 0.67945 -0.3048)
			(stroke
				(width 0.1)
				(type default)
			)
			(layer "F.Fab")
		)
		(fp_line
			(start 0.120396 0.3048)
			(end 0.120396 0.2794)
			(stroke
				(width 0.1)
				(type default)
			)
			(layer "F.Fab")
		)
		(fp_line
			(start 0.120396 0.2794)
			(end -0.12065 0.2794)
			(stroke
				(width 0.1)
				(type default)
			)
			(layer "F.Fab")
		)
		(fp_line
			(start -0.12065 0.3048)
			(end -0.67945 0.3048)
			(stroke
				(width 0.1)
				(type default)
			)
			(layer "F.Fab")
		)
		(fp_line
			(start -0.12065 0.2794)
			(end -0.12065 0.3048)
			(stroke
				(width 0.1)
				(type default)
			)
			(layer "F.Fab")
		)
		(fp_line
			(start -0.12065 -0.2794)
			(end 0.12065 -0.2794)
			(stroke
				(width 0.1)
				(type default)
			)
			(layer "F.Fab")
		)
		(fp_line
			(start -0.12065 -0.305054)
			(end -0.12065 -0.2794)
			(stroke
				(width 0.1)
				(type default)
			)
			(layer "F.Fab")
		)
		(fp_line
			(start -0.67945 0.3048)
			(end -0.67945 -0.305054)
			(stroke
				(width 0.1)
				(type default)
			)
			(layer "F.Fab")
		)
		(fp_line
			(start -0.67945 -0.305054)
			(end -0.12065 -0.305054)
			(stroke
				(width 0.1)
				(type default)
			)
			(layer "F.Fab")
		)
		(pad "1" smd circle
			(at -0.40005 0 180)
			(size 0 0)
			(layers "F.Cu" "F.Mask" "F.Paste")
			(net "P3V3_AUX")
		)
		(pad "2" smd circle
			(at 0.40005 0 180)
			(size 0 0)
			(layers "F.Cu" "F.Mask" "F.Paste")
			(net "FM_SLPS3_N")
		)
	)
)
